(kicad_pcb
	(version 20260206)
	(generator "pcbnew")
	(generator_version "10.0")
	(general
		(thickness 1.6)
		(legacy_teardrops no)
	)
	(paper "A4")
	(title_block
		(title "01162023_DA0F0TEBIF0_F0T_Expander_BD_F_brd_V02_OCP.brd")
		(comment 1 "Grand Teton / footprints 3048-3053 of 9728")
	)
	(layers
		(0 "F.Cu" signal "TOP")
		(4 "In1.Cu" signal "GND")
		(6 "In2.Cu" signal "VCC")
		(8 "In3.Cu" signal "VCC1")
		(10 "In4.Cu" signal "GND1")
		(12 "In5.Cu" signal "IN1")
		(14 "In6.Cu" signal "GND2")
		(16 "In7.Cu" signal "IN2")
		(18 "In8.Cu" signal "GND3")
		(20 "In9.Cu" signal "IN3")
		(22 "In10.Cu" signal "GND4")
		(24 "In11.Cu" signal "IN4")
		(26 "In12.Cu" signal "GND5")
		(28 "In13.Cu" signal "IN5")
		(30 "In14.Cu" signal "GND6")
		(32 "In15.Cu" signal "IN6")
		(34 "In16.Cu" signal "GND7")
		(2 "B.Cu" signal "BOTTOM")
		(9 "F.Adhes" user "F.Adhesive")
		(11 "B.Adhes" user "B.Adhesive")
		(13 "F.Paste" user "Package Geometry/Pastemask Top")
		(15 "B.Paste" user "Package Geometry/Pastemask Bottom")
		(5 "F.SilkS" user "Ref Des/Silkscreen Top")
		(7 "B.SilkS" user "Ref Des/Silkscreen Bottom")
		(1 "F.Mask" user "Board Geometry/Soldermask Top")
		(3 "B.Mask" user "Board Geometry/Soldermask Bottom")
		(17 "Dwgs.User" user "User.Drawings")
		(19 "Cmts.User" user "User.Comments")
		(21 "Eco1.User" user "User.Eco1")
		(23 "Eco2.User" user "User.Eco2")
		(25 "Edge.Cuts" user "Board Geometry/Outline")
		(27 "Margin" user)
		(31 "F.CrtYd" user "Package Geometry/Place Bound Top")
		(29 "B.CrtYd" user "Package Geometry/Place Bound Bottom")
		(35 "F.Fab" user "Ref Des/Assembly Top")
		(33 "B.Fab" user "Ref Des/Assembly Bottom")
	)
	(footprint ""
		(layer "F.Cu")
		(at 352.320098 -147.654518)
		(property "Reference" "R4829"
			(at 0 0 0)
			(layer "F.SilkS")
			(hide yes)
			(effects
				(font
					(size 1.27 1.27)
				)
			)
		)
		(property "Value" ""
			(at 0 0 0)
			(layer "F.Fab")
			(effects
				(font
					(size 1.27 1.27)
				)
			)
		)
		(duplicate_pad_numbers_are_jumpers no)
		(fp_line
			(start -0.7874 -0.4064)
			(end 0.7874 -0.4064)
			(stroke
				(width 0.1524)
				(type default)
			)
			(layer "F.SilkS")
		)
		(fp_line
			(start -0.7874 0.4064)
			(end -0.7874 -0.4064)
			(stroke
				(width 0.1524)
				(type default)
			)
			(layer "F.SilkS")
		)
		(fp_line
			(start 0.7874 -0.4064)
			(end 0.7874 0.4064)
			(stroke
				(width 0.1524)
				(type default)
			)
			(layer "F.SilkS")
		)
		(fp_line
			(start 0.7874 0.4064)
			(end -0.7874 0.4064)
			(stroke
				(width 0.1524)
				(type default)
			)
			(layer "F.SilkS")
		)
		(fp_line
			(start -0.67945 -0.305054)
			(end -0.12065 -0.305054)
			(stroke
				(width 0.1)
				(type default)
			)
			(layer "F.Fab")
		)
		(fp_line
			(start -0.67945 0.3048)
			(end -0.67945 -0.305054)
			(stroke
				(width 0.1)
				(type default)
			)
			(layer "F.Fab")
		)
		(fp_line
			(start -0.12065 -0.305054)
			(end -0.12065 -0.2794)
			(stroke
				(width 0.1)
				(type default)
			)
			(layer "F.Fab")
		)
		(fp_line
			(start -0.12065 -0.2794)
			(end 0.12065 -0.2794)
			(stroke
				(width 0.1)
				(type default)
			)
			(layer "F.Fab")
		)
		(fp_line
			(start -0.12065 0.2794)
			(end -0.12065 0.3048)
			(stroke
				(width 0.1)
				(type default)
			)
			(layer "F.Fab")
		)
		(fp_line
			(start -0.12065 0.3048)
			(end -0.67945 0.3048)
			(stroke
				(width 0.1)
				(type default)
			)
			(layer "F.Fab")
		)
		(fp_line
			(start 0.120396 0.2794)
			(end -0.12065 0.2794)
			(stroke
				(width 0.1)
				(type default)
			)
			(layer "F.Fab")
		)
		(fp_line
			(start 0.120396 0.3048)
			(end 0.120396 0.2794)
			(stroke
				(width 0.1)
				(type default)
			)
			(layer "F.Fab")
		)
		(fp_line
			(start 0.12065 -0.3048)
			(end 0.67945 -0.3048)
			(stroke
				(width 0.1)
				(type default)
			)
			(layer "F.Fab")
		)
		(fp_line
			(start 0.12065 -0.2794)
			(end 0.12065 -0.3048)
			(stroke
				(width 0.1)
				(type default)
			)
			(layer "F.Fab")
		)
		(fp_line
			(start 0.67945 -0.3048)
			(end 0.67945 0.3048)
			(stroke
				(width 0.1)
				(type default)
			)
			(layer "F.Fab")
		)
		(fp_line
			(start 0.67945 0.3048)
			(end 0.120396 0.3048)
			(stroke
				(width 0.1)
				(type default)
			)
			(layer "F.Fab")
		)
		(pad "1" smd circle
			(at -0.40005 0)
			(size 0 0)
			(layers "F.Cu" "F.Mask" "F.Paste")
			(net "PCA9555_1_PEX3_A0")
		)
		(pad "2" smd circle
			(at 0.40005 0)
			(size 0 0)
			(layers "F.Cu" "F.Mask" "F.Paste")
			(net "P3V3_AUX")
		)
	)
	(footprint ""
		(layer "F.Cu")
		(at 336.467704 -56.353456)
		(property "Reference" "C2875"
			(at 0 0 0)
			(layer "F.SilkS")
			(hide yes)
			(effects
				(font
					(size 1.27 1.27)
				)
			)
		)
		(property "Value" ""
			(at 0 0 0)
			(layer "F.Fab")
			(effects
				(font
					(size 1.27 1.27)
				)
			)
		)
		(duplicate_pad_numbers_are_jumpers no)
		(fp_line
			(start -0.7874 -0.4064)
			(end 0.7874 -0.4064)
			(stroke
				(width 0.1524)
				(type default)
			)
			(layer "F.SilkS")
		)
		(fp_line
			(start -0.7874 0.4064)
			(end -0.7874 -0.4064)
			(stroke
				(width 0.1524)
				(type default)
			)
			(layer "F.SilkS")
		)
		(fp_line
			(start 0.7874 -0.4064)
			(end 0.7874 0.4064)
			(stroke
				(width 0.1524)
				(type default)
			)
			(layer "F.SilkS")
		)
		(fp_line
			(start 0.7874 0.4064)
			(end -0.7874 0.4064)
			(stroke
				(width 0.1524)
				(type default)
			)
			(layer "F.SilkS")
		)
		(fp_line
			(start -0.67945 -0.305054)
			(end -0.12065 -0.305054)
			(stroke
				(width 0.1)
				(type default)
			)
			(layer "F.Fab")
		)
		(fp_line
			(start -0.67945 0.3048)
			(end -0.67945 -0.305054)
			(stroke
				(width 0.1)
				(type default)
			)
			(layer "F.Fab")
		)
		(fp_line
			(start -0.12065 -0.305054)
			(end -0.12065 -0.2794)
			(stroke
				(width 0.1)
				(type default)
			)
			(layer "F.Fab")
		)
		(fp_line
			(start -0.12065 -0.2794)
			(end 0.12065 -0.2794)
			(stroke
				(width 0.1)
				(type default)
			)
			(layer "F.Fab")
		)
		(fp_line
			(start -0.12065 0.2794)
			(end -0.12065 0.3048)
			(stroke
				(width 0.1)
				(type default)
			)
			(layer "F.Fab")
		)
		(fp_line
			(start -0.12065 0.3048)
			(end -0.67945 0.3048)
			(stroke
				(width 0.1)
				(type default)
			)
			(layer "F.Fab")
		)
		(fp_line
			(start 0.120396 0.2794)
			(end -0.12065 0.2794)
			(stroke
				(width 0.1)
				(type default)
			)
			(layer "F.Fab")
		)
		(fp_line
			(start 0.120396 0.3048)
			(end 0.120396 0.2794)
			(stroke
				(width 0.1)
				(type default)
			)
			(layer "F.Fab")
		)
		(fp_line
			(start 0.12065 -0.3048)
			(end 0.67945 -0.3048)
			(stroke
				(width 0.1)
				(type default)
			)
			(layer "F.Fab")
		)
		(fp_line
			(start 0.12065 -0.2794)
			(end 0.12065 -0.3048)
			(stroke
				(width 0.1)
				(type default)
			)
			(layer "F.Fab")
		)
		(fp_line
			(start 0.67945 -0.3048)
			(end 0.67945 0.3048)
			(stroke
				(width 0.1)
				(type default)
			)
			(layer "F.Fab")
		)
		(fp_line
			(start 0.67945 0.3048)
			(end 0.120396 0.3048)
			(stroke
				(width 0.1)
				(type default)
			)
			(layer "F.Fab")
		)
		(pad "1" smd circle
			(at -0.40005 0)
			(size 0 0)
			(layers "F.Cu" "F.Mask" "F.Paste")
			(net "SSD11_PWR_EN_R")
		)
		(pad "2" smd circle
			(at 0.40005 0)
			(size 0 0)
			(layers "F.Cu" "F.Mask" "F.Paste")
			(net "GND")
		)
	)
	(footprint ""
		(layer "F.Cu")
		(at 447.247264 -20.35556)
		(property "Reference" "C3981"
			(at 0 0 0)
			(layer "F.SilkS")
			(hide yes)
			(effects
				(font
					(size 1.27 1.27)
				)
			)
		)
		(property "Value" ""
			(at 0 0 0)
			(layer "F.Fab")
			(effects
				(font
					(size 1.27 1.27)
				)
			)
		)
		(duplicate_pad_numbers_are_jumpers no)
		(fp_line
			(start -0.7874 -0.4064)
			(end 0.7874 -0.4064)
			(stroke
				(width 0.1524)
				(type default)
			)
			(layer "F.SilkS")
		)
		(fp_line
			(start -0.7874 0.4064)
			(end -0.7874 -0.4064)
			(stroke
				(width 0.1524)
				(type default)
			)
			(layer "F.SilkS")
		)
		(fp_line
			(start 0.7874 -0.4064)
			(end 0.7874 0.4064)
			(stroke
				(width 0.1524)
				(type default)
			)
			(layer "F.SilkS")
		)
		(fp_line
			(start 0.7874 0.4064)
			(end -0.7874 0.4064)
			(stroke
				(width 0.1524)
				(type default)
			)
			(layer "F.SilkS")
		)
		(fp_line
			(start -0.67945 -0.305054)
			(end -0.12065 -0.305054)
			(stroke
				(width 0.1)
				(type default)
			)
			(layer "F.Fab")
		)
		(fp_line
			(start -0.67945 0.3048)
			(end -0.67945 -0.305054)
			(stroke
				(width 0.1)
				(type default)
			)
			(layer "F.Fab")
		)
		(fp_line
			(start -0.12065 -0.305054)
			(end -0.12065 -0.2794)
			(stroke
				(width 0.1)
				(type default)
			)
			(layer "F.Fab")
		)
		(fp_line
			(start -0.12065 -0.2794)
			(end 0.12065 -0.2794)
			(stroke
				(width 0.1)
				(type default)
			)
			(layer "F.Fab")
		)
		(fp_line
			(start -0.12065 0.2794)
			(end -0.12065 0.3048)
			(stroke
				(width 0.1)
				(type default)
			)
			(layer "F.Fab")
		)
		(fp_line
			(start -0.12065 0.3048)
			(end -0.67945 0.3048)
			(stroke
				(width 0.1)
				(type default)
			)
			(layer "F.Fab")
		)
		(fp_line
			(start 0.120396 0.2794)
			(end -0.12065 0.2794)
			(stroke
				(width 0.1)
				(type default)
			)
			(layer "F.Fab")
		)
		(fp_line
			(start 0.120396 0.3048)
			(end 0.120396 0.2794)
			(stroke
				(width 0.1)
				(type default)
			)
			(layer "F.Fab")
		)
		(fp_line
			(start 0.12065 -0.3048)
			(end 0.67945 -0.3048)
			(stroke
				(width 0.1)
				(type default)
			)
			(layer "F.Fab")
		)
		(fp_line
			(start 0.12065 -0.2794)
			(end 0.12065 -0.3048)
			(stroke
				(width 0.1)
				(type default)
			)
			(layer "F.Fab")
		)
		(fp_line
			(start 0.67945 -0.3048)
			(end 0.67945 0.3048)
			(stroke
				(width 0.1)
				(type default)
			)
			(layer "F.Fab")
		)
		(fp_line
			(start 0.67945 0.3048)
			(end 0.120396 0.3048)
			(stroke
				(width 0.1)
				(type default)
			)
			(layer "F.Fab")
		)
		(pad "1" smd circle
			(at -0.40005 0)
			(size 0 0)
			(layers "F.Cu" "F.Mask" "F.Paste")
			(net "P12V_SSD15")
		)
		(pad "2" smd circle
			(at 0.40005 0)
			(size 0 0)
			(layers "F.Cu" "F.Mask" "F.Paste")
			(net "GND")
		)
	)
	(footprint ""
		(layer "F.Cu")
		(at 364.494826 -111.377476 -90)
		(property "Reference" "PC914"
			(at 0 0 270)
			(layer "F.SilkS")
			(hide yes)
			(effects
				(font
					(size 1.27 1.27)
				)
			)
		)
		(property "Value" ""
			(at 0 0 270)
			(layer "F.Fab")
			(effects
				(font
					(size 1.27 1.27)
				)
			)
		)
		(duplicate_pad_numbers_are_jumpers no)
		(fp_line
			(start -0.7874 0.4064)
			(end -0.7874 -0.4064)
			(stroke
				(width 0.1524)
				(type default)
			)
			(layer "F.SilkS")
		)
		(fp_line
			(start 0.7874 0.4064)
			(end -0.7874 0.4064)
			(stroke
				(width 0.1524)
				(type default)
			)
			(layer "F.SilkS")
		)
		(fp_line
			(start -0.7874 -0.4064)
			(end 0.7874 -0.4064)
			(stroke
				(width 0.1524)
				(type default)
			)
			(layer "F.SilkS")
		)
		(fp_line
			(start 0.7874 -0.4064)
			(end 0.7874 0.4064)
			(stroke
				(width 0.1524)
				(type default)
			)
			(layer "F.SilkS")
		)
		(fp_line
			(start -0.67945 0.3048)
			(end -0.67945 -0.305054)
			(stroke
				(width 0.1)
				(type default)
			)
			(layer "F.Fab")
		)
		(fp_line
			(start -0.12065 0.3048)
			(end -0.67945 0.3048)
			(stroke
				(width 0.1)
				(type default)
			)
			(layer "F.Fab")
		)
		(fp_line
			(start 0.120396 0.3048)
			(end 0.120396 0.2794)
			(stroke
				(width 0.1)
				(type default)
			)
			(layer "F.Fab")
		)
		(fp_line
			(start 0.67945 0.3048)
			(end 0.120396 0.3048)
			(stroke
				(width 0.1)
				(type default)
			)
			(layer "F.Fab")
		)
		(fp_line
			(start -0.12065 0.2794)
			(end -0.12065 0.3048)
			(stroke
				(width 0.1)
				(type default)
			)
			(layer "F.Fab")
		)
		(fp_line
			(start 0.120396 0.2794)
			(end -0.12065 0.2794)
			(stroke
				(width 0.1)
				(type default)
			)
			(layer "F.Fab")
		)
		(fp_line
			(start -0.12065 -0.2794)
			(end 0.12065 -0.2794)
			(stroke
				(width 0.1)
				(type default)
			)
			(layer "F.Fab")
		)
		(fp_line
			(start 0.12065 -0.2794)
			(end 0.12065 -0.3048)
			(stroke
				(width 0.1)
				(type default)
			)
			(layer "F.Fab")
		)
		(fp_line
			(start 0.12065 -0.3048)
			(end 0.67945 -0.3048)
			(stroke
				(width 0.1)
				(type default)
			)
			(layer "F.Fab")
		)
		(fp_line
			(start 0.67945 -0.3048)
			(end 0.67945 0.3048)
			(stroke
				(width 0.1)
				(type default)
			)
			(layer "F.Fab")
		)
		(fp_line
			(start -0.67945 -0.305054)
			(end -0.12065 -0.305054)
			(stroke
				(width 0.1)
				(type default)
			)
			(layer "F.Fab")
		)
		(fp_line
			(start -0.12065 -0.305054)
			(end -0.12065 -0.2794)
			(stroke
				(width 0.1)
				(type default)
			)
			(layer "F.Fab")
		)
		(pad "1" smd circle
			(at -0.40005 0 270)
			(size 0 0)
			(layers "F.Cu" "F.Mask" "F.Paste")
			(net "P3V3_NIC6_CO_MODE")
		)
		(pad "2" smd circle
			(at 0.40005 0 270)
			(size 0 0)
			(layers "F.Cu" "F.Mask" "F.Paste")
			(net "GND")
		)
	)
	(footprint ""
		(layer "F.Cu")
		(at 410.972508 -210.341718 180)
		(property "Reference" "R6443"
			(at 0 0 180)
			(layer "F.SilkS")
			(hide yes)
			(effects
				(font
					(size 1.27 1.27)
				)
			)
		)
		(property "Value" ""
			(at 0 0 180)
			(layer "F.Fab")
			(effects
				(font
					(size 1.27 1.27)
				)
			)
		)
		(duplicate_pad_numbers_are_jumpers no)
		(fp_line
			(start 0.7874 0.4064)
			(end -0.7874 0.4064)
			(stroke
				(width 0.1524)
				(type default)
			)
			(layer "F.SilkS")
		)
		(fp_line
			(start 0.7874 -0.4064)
			(end 0.7874 0.4064)
			(stroke
				(width 0.1524)
				(type default)
			)
			(layer "F.SilkS")
		)
		(fp_line
			(start -0.7874 0.4064)
			(end -0.7874 -0.4064)
			(stroke
				(width 0.1524)
				(type default)
			)
			(layer "F.SilkS")
		)
		(fp_line
			(start -0.7874 -0.4064)
			(end 0.7874 -0.4064)
			(stroke
				(width 0.1524)
				(type default)
			)
			(layer "F.SilkS")
		)
		(fp_line
			(start 0.67945 0.3048)
			(end 0.120396 0.3048)
			(stroke
				(width 0.1)
				(type default)
			)
			(layer "F.Fab")
		)
		(fp_line
			(start 0.67945 -0.3048)
			(end 0.67945 0.3048)
			(stroke
				(width 0.1)
				(type default)
			)
			(layer "F.Fab")
		)
		(fp_line
			(start 0.12065 -0.2794)
			(end 0.12065 -0.3048)
			(stroke
				(width 0.1)
				(type default)
			)
			(layer "F.Fab")
		)
		(fp_line
			(start 0.12065 -0.3048)
			(end 0.67945 -0.3048)
			(stroke
				(width 0.1)
				(type default)
			)
			(layer "F.Fab")
		)
		(fp_line
			(start 0.120396 0.3048)
			(end 0.120396 0.2794)
			(stroke
				(width 0.1)
				(type default)
			)
			(layer "F.Fab")
		)
		(fp_line
			(start 0.120396 0.2794)
			(end -0.12065 0.2794)
			(stroke
				(width 0.1)
				(type default)
			)
			(layer "F.Fab")
		)
		(fp_line
			(start -0.12065 0.3048)
			(end -0.67945 0.3048)
			(stroke
				(width 0.1)
				(type default)
			)
			(layer "F.Fab")
		)
		(fp_line
			(start -0.12065 0.2794)
			(end -0.12065 0.3048)
			(stroke
				(width 0.1)
				(type default)
			)
			(layer "F.Fab")
		)
		(fp_line
			(start -0.12065 -0.2794)
			(end 0.12065 -0.2794)
			(stroke
				(width 0.1)
				(type default)
			)
			(layer "F.Fab")
		)
		(fp_line
			(start -0.12065 -0.305054)
			(end -0.12065 -0.2794)
			(stroke
				(width 0.1)
				(type default)
			)
			(layer "F.Fab")
		)
		(fp_line
			(start -0.67945 0.3048)
			(end -0.67945 -0.305054)
			(stroke
				(width 0.1)
				(type default)
			)
			(layer "F.Fab")
		)
		(fp_line
			(start -0.67945 -0.305054)
			(end -0.12065 -0.305054)
			(stroke
				(width 0.1)
				(type default)
			)
			(layer "F.Fab")
		)
		(pad "1" smd circle
			(at -0.40005 0 180)
			(size 0 0)
			(layers "F.Cu" "F.Mask" "F.Paste")
			(net "FPGA_PEX3_MODE_SEL1_D_N")
		)
		(pad "2" smd circle
			(at 0.40005 0 180)
			(size 0 0)
			(layers "F.Cu" "F.Mask" "F.Paste")
			(net "P3V3_AUX")
		)
	)
	(footprint ""
		(layer "F.Cu")
		(at 78.61046 -18.61439 90)
		(property "Reference" "U128"
			(at -1.49479 2.26441 90)
			(unlocked yes)
			(layer "F.SilkS")
			(effects
				(font
					(size 0.7874 0.5842)
					(thickness 0.1524)
				)
				(justify left)
			)
		)
		(property "Value" ""
			(at 0 0 90)
			(layer "F.Fab")
			(effects
				(font
					(size 1.27 1.27)
				)
			)
		)
		(duplicate_pad_numbers_are_jumpers no)
		(fp_line
			(start 1.463548 -1.549908)
			(end 1.463548 1.549908)
			(stroke
				(width 0.1524)
				(type default)
			)
			(layer "F.SilkS")
		)
		(fp_line
			(start 0.762 -1.549908)
			(end 1.463548 -1.549908)
			(stroke
				(width 0.1524)
				(type default)
			)
			(layer "F.SilkS")
		)
		(fp_line
			(start -0.787908 -1.549908)
			(end 0 -0.762)
			(stroke
				(width 0.1524)
				(type default)
			)
			(layer "F.SilkS")
		)
		(fp_line
			(start -1.463548 -1.549908)
			(end -0.787908 -1.549908)
			(stroke
				(width 0.1524)
				(type default)
			)
			(layer "F.SilkS")
		)
		(fp_line
			(start 0 -0.762)
			(end 0.762 -1.549908)
			(stroke
				(width 0.1524)
				(type default)
			)
			(layer "F.SilkS")
		)
		(fp_line
			(start 1.463548 1.549908)
			(end -1.463548 1.549908)
			(stroke
				(width 0.1524)
				(type default)
			)
			(layer "F.SilkS")
		)
		(fp_line
			(start -1.463548 1.549908)
			(end -1.463548 -1.549908)
			(stroke
				(width 0.1524)
				(type default)
			)
			(layer "F.SilkS")
		)
		(fp_poly
			(pts
				(xy -3.4798 -1.359916) (xy -2.86004 -1.050036) (xy -3.4798 -0.740156)
			)
			(stroke
				(width 0)
				(type default)
			)
			(fill yes)
			(layer "F.SilkS")
		)
		(fp_line
			(start 1.549908 -1.549908)
			(end 1.549908 1.549908)
			(stroke
				(width 0.1)
				(type default)
			)
			(layer "F.Fab")
		)
		(fp_line
			(start -1.549908 -1.549908)
			(end 1.549908 -1.549908)
			(stroke
				(width 0.1)
				(type default)
			)
			(layer "F.Fab")
		)
		(fp_line
			(start 1.549908 1.549908)
			(end -1.549908 1.549908)
			(stroke
				(width 0.1)
				(type default)
			)
			(layer "F.Fab")
		)
		(fp_line
			(start -1.549908 1.549908)
			(end -1.549908 -1.549908)
			(stroke
				(width 0.1)
				(type default)
			)
			(layer "F.Fab")
		)
		(fp_poly
			(pts
				(xy -3.4798 -1.359916) (xy -2.86004 -1.050036) (xy -3.4798 -0.740156)
			)
			(stroke
				(width 0)
				(type default)
			)
			(fill yes)
			(layer "F.Fab")
		)
		(pad "1" smd rect
			(at -2.175002 -1.050036 180)
			(size 0.6096 1.1684)
			(layers "F.Cu" "F.Mask" "F.Paste")
			(net "P3V3_SSD2")
		)
		(pad "2" smd rect
			(at -2.175002 -0.32512 180)
			(size 0.4318 1.1684)
			(layers "F.Cu" "F.Mask" "F.Paste")
			(net "SMB_ISO_SSD2_SCL")
		)
		(pad "3" smd rect
			(at -2.175002 0.32512 180)
			(size 0.4318 1.1684)
			(layers "F.Cu" "F.Mask" "F.Paste")
			(net "SMB_ISO_SSD2_SDA")
		)
		(pad "4" smd rect
			(at -2.175002 1.050036 180)
			(size 0.6096 1.1684)
			(layers "F.Cu" "F.Mask" "F.Paste")
			(net "GND")
		)
		(pad "5" smd rect
			(at 2.175002 1.050036 180)
			(size 0.6096 1.1684)
			(layers "F.Cu" "F.Mask" "F.Paste")
			(net "SMB_SSD2_ISO_EN")
		)
		(pad "6" smd rect
			(at 2.175002 0.32512 180)
			(size 0.4318 1.1684)
			(layers "F.Cu" "F.Mask" "F.Paste")
			(net "SMB_BIC_I2C9_MUX0_SSD2_R_SDA")
		)
		(pad "7" smd rect
			(at 2.175002 -0.32512 180)
			(size 0.4318 1.1684)
			(layers "F.Cu" "F.Mask" "F.Paste")
			(net "SMB_BIC_I2C9_MUX0_SSD2_R_SCL")
		)
		(pad "8" smd rect
			(at 2.175002 -1.050036 180)
			(size 0.6096 1.1684)
			(layers "F.Cu" "F.Mask" "F.Paste")
			(net "P3V3_AUX")
		)
	)
)
